# T6G (Grand Teton) — schematic netlist excerpt (pin names and nets, part order shuffled) for the footprints in the layout excerpt that follows; sources: Cadence DE-HDL packaged netlist, KiCad conversion of 04192023_DAF0TMB3IC0_F0TG_MB_C_brd_V02_OCP.brd

PC618_IOP1_4  Q_CAP  2.2UF 10V 10% X6S  pkg C0402  page 223 : A = PVDDCR_CPU1_P1_PVCC ; B = GND
R703  Q_RES  10K 5% EMPTY  pkg 0402LF  page 78 : A = PWRGD_CPU1_PWROK ; B = GND

(kicad_pcb
	(version 20260206)
	(generator "pcbnew")
	(generator_version "10.0")
	(general
		(thickness 1.6)
		(legacy_teardrops no)
	)
	(paper "A4")
	(title_block
		(title "04192023_DAF0TMB3IC0_F0TG_MB_C_brd_V02_OCP.brd")
		(comment 1 "Grand Teton / footprints 3326-3327 of 8354")
	)
	(layers
		(0 "F.Cu" signal "TOP")
		(4 "In1.Cu" signal "GND")
		(6 "In2.Cu" signal "IN1")
		(8 "In3.Cu" signal "GND1")
		(10 "In4.Cu" signal "IN2")
		(12 "In5.Cu" signal "GND2")
		(14 "In6.Cu" signal "IN3")
		(16 "In7.Cu" signal "GND3")
		(18 "In8.Cu" signal "VCC")
		(20 "In9.Cu" signal "VCC1")
		(22 "In10.Cu" signal "GND4")
		(24 "In11.Cu" signal "IN4")
		(26 "In12.Cu" signal "GND5")
		(28 "In13.Cu" signal "IN5")
		(30 "In14.Cu" signal "GND6")
		(32 "In15.Cu" signal "IN6")
		(34 "In16.Cu" signal "GND7")
		(2 "B.Cu" signal "BOTTOM")
		(9 "F.Adhes" user "F.Adhesive")
		(11 "B.Adhes" user "B.Adhesive")
		(13 "F.Paste" user "Package Geometry/Pastemask Top")
		(15 "B.Paste" user "Package Geometry/Pastemask Bottom")
		(5 "F.SilkS" user "Ref Des/Silkscreen Top")
		(7 "B.SilkS" user "Ref Des/Silkscreen Bottom")
		(1 "F.Mask" user "Board Geometry/Soldermask Top")
		(3 "B.Mask" user "Board Geometry/Soldermask Bottom")
		(17 "Dwgs.User" user "User.Drawings")
		(19 "Cmts.User" user "User.Comments")
		(21 "Eco1.User" user "User.Eco1")
		(23 "Eco2.User" user "User.Eco2")
		(25 "Edge.Cuts" user "Board Geometry/Outline")
		(27 "Margin" user)
		(31 "F.CrtYd" user "Package Geometry/Place Bound Top")
		(29 "B.CrtYd" user "Package Geometry/Place Bound Bottom")
		(35 "F.Fab" user "Ref Des/Assembly Top")
		(33 "B.Fab" user "Ref Des/Assembly Bottom")
	)
	(footprint ""
		(layer "F.Cu")
		(at 24.917654 -346.719398 -90)
		(property "Reference" "PC618_IOP1_4"
			(at 0 0 270)
			(layer "F.SilkS")
			(hide yes)
			(effects
				(font
					(size 1.27 1.27)
				)
			)
		)
		(property "Value" ""
			(at 0 0 270)
			(layer "F.Fab")
			(effects
				(font
					(size 1.27 1.27)
				)
			)
		)
		(duplicate_pad_numbers_are_jumpers no)
		(fp_line
			(start -0.7874 0.4064)
			(end -0.7874 -0.4064)
			(stroke
				(width 0.1524)
				(type default)
			)
			(layer "F.SilkS")
		)
		(fp_line
			(start 0.7874 0.4064)
			(end -0.7874 0.4064)
			(stroke
				(width 0.1524)
				(type default)
			)
			(layer "F.SilkS")
		)
		(fp_line
			(start -0.7874 -0.4064)
			(end 0.7874 -0.4064)
			(stroke
				(width 0.1524)
				(type default)
			)
			(layer "F.SilkS")
		)
		(fp_line
			(start 0.7874 -0.4064)
			(end 0.7874 0.4064)
			(stroke
				(width 0.1524)
				(type default)
			)
			(layer "F.SilkS")
		)
		(fp_line
			(start -0.67945 0.3048)
			(end -0.67945 -0.305054)
			(stroke
				(width 0.1)
				(type default)
			)
			(layer "F.Fab")
		)
		(fp_line
			(start -0.12065 0.3048)
			(end -0.67945 0.3048)
			(stroke
				(width 0.1)
				(type default)
			)
			(layer "F.Fab")
		)
		(fp_line
			(start 0.120396 0.3048)
			(end 0.120396 0.2794)
			(stroke
				(width 0.1)
				(type default)
			)
			(layer "F.Fab")
		)
		(fp_line
			(start 0.67945 0.3048)
			(end 0.120396 0.3048)
			(stroke
				(width 0.1)
				(type default)
			)
			(layer "F.Fab")
		)
		(fp_line
			(start -0.12065 0.2794)
			(end -0.12065 0.3048)
			(stroke
				(width 0.1)
				(type default)
			)
			(layer "F.Fab")
		)
		(fp_line
			(start 0.120396 0.2794)
			(end -0.12065 0.2794)
			(stroke
				(width 0.1)
				(type default)
			)
			(layer "F.Fab")
		)
		(fp_line
			(start -0.12065 -0.2794)
			(end 0.12065 -0.2794)
			(stroke
				(width 0.1)
				(type default)
			)
			(layer "F.Fab")
		)
		(fp_line
			(start 0.12065 -0.2794)
			(end 0.12065 -0.3048)
			(stroke
				(width 0.1)
				(type default)
			)
			(layer "F.Fab")
		)
		(fp_line
			(start 0.12065 -0.3048)
			(end 0.67945 -0.3048)
			(stroke
				(width 0.1)
				(type default)
			)
			(layer "F.Fab")
		)
		(fp_line
			(start 0.67945 -0.3048)
			(end 0.67945 0.3048)
			(stroke
				(width 0.1)
				(type default)
			)
			(layer "F.Fab")
		)
		(fp_line
			(start -0.67945 -0.305054)
			(end -0.12065 -0.305054)
			(stroke
				(width 0.1)
				(type default)
			)
			(layer "F.Fab")
		)
		(fp_line
			(start -0.12065 -0.305054)
			(end -0.12065 -0.2794)
			(stroke
				(width 0.1)
				(type default)
			)
			(layer "F.Fab")
		)
		(pad "1" smd circle
			(at -0.40005 0 270)
			(size 0 0)
			(layers "F.Cu" "F.Mask" "F.Paste")
			(net "PVDDCR_CPU1_P1_PVCC")
		)
		(pad "2" smd circle
			(at 0.40005 0 270)
			(size 0 0)
			(layers "F.Cu" "F.Mask" "F.Paste")
			(net "GND")
		)
	)
	(footprint ""
		(layer "F.Cu")
		(at 83.157314 -138.562334)
		(property "Reference" "R703"
			(at 0 0 0)
			(layer "F.SilkS")
			(hide yes)
			(effects
				(font
					(size 1.27 1.27)
				)
			)
		)
		(property "Value" ""
			(at 0 0 0)
			(layer "F.Fab")
			(effects
				(font
					(size 1.27 1.27)
				)
			)
		)
		(duplicate_pad_numbers_are_jumpers no)
		(fp_line
			(start -0.7874 -0.4064)
			(end 0.7874 -0.4064)
			(stroke
				(width 0.1524)
				(type default)
			)
			(layer "F.SilkS")
		)
		(fp_line
			(start -0.7874 0.4064)
			(end -0.7874 -0.4064)
			(stroke
				(width 0.1524)
				(type default)
			)
			(layer "F.SilkS")
		)
		(fp_line
			(start 0.7874 -0.4064)
			(end 0.7874 0.4064)
			(stroke
				(width 0.1524)
				(type default)
			)
			(layer "F.SilkS")
		)
		(fp_line
			(start 0.7874 0.4064)
			(end -0.7874 0.4064)
			(stroke
				(width 0.1524)
				(type default)
			)
			(layer "F.SilkS")
		)
		(fp_line
			(start -0.67945 -0.305054)
			(end -0.12065 -0.305054)
			(stroke
				(width 0.1)
				(type default)
			)
			(layer "F.Fab")
		)
		(fp_line
			(start -0.67945 0.3048)
			(end -0.67945 -0.305054)
			(stroke
				(width 0.1)
				(type default)
			)
			(layer "F.Fab")
		)
		(fp_line
			(start -0.12065 -0.305054)
			(end -0.12065 -0.2794)
			(stroke
				(width 0.1)
				(type default)
			)
			(layer "F.Fab")
		)
		(fp_line
			(start -0.12065 -0.2794)
			(end 0.12065 -0.2794)
			(stroke
				(width 0.1)
				(type default)
			)
			(layer "F.Fab")
		)
		(fp_line
			(start -0.12065 0.2794)
			(end -0.12065 0.3048)
			(stroke
				(width 0.1)
				(type default)
			)
			(layer "F.Fab")
		)
		(fp_line
			(start -0.12065 0.3048)
			(end -0.67945 0.3048)
			(stroke
				(width 0.1)
				(type default)
			)
			(layer "F.Fab")
		)
		(fp_line
			(start 0.120396 0.2794)
			(end -0.12065 0.2794)
			(stroke
				(width 0.1)
				(type default)
			)
			(layer "F.Fab")
		)
		(fp_line
			(start 0.120396 0.3048)
			(end 0.120396 0.2794)
			(stroke
				(width 0.1)
				(type default)
			)
			(layer "F.Fab")
		)
		(fp_line
			(start 0.12065 -0.3048)
			(end 0.67945 -0.3048)
			(stroke
				(width 0.1)
				(type default)
			)
			(layer "F.Fab")
		)
		(fp_line
			(start 0.12065 -0.2794)
			(end 0.12065 -0.3048)
			(stroke
				(width 0.1)
				(type default)
			)
			(layer "F.Fab")
		)
		(fp_line
			(start 0.67945 -0.3048)
			(end 0.67945 0.3048)
			(stroke
				(width 0.1)
				(type default)
			)
			(layer "F.Fab")
		)
		(fp_line
			(start 0.67945 0.3048)
			(end 0.120396 0.3048)
			(stroke
				(width 0.1)
				(type default)
			)
			(layer "F.Fab")
		)
		(pad "1" smd circle
			(at -0.40005 0)
			(size 0 0)
			(layers "F.Cu" "F.Mask" "F.Paste")
			(net "PWRGD_CPU1_PWROK")
		)
		(pad "2" smd circle
			(at 0.40005 0)
			(size 0 0)
			(layers "F.Cu" "F.Mask" "F.Paste")
			(net "GND")
		)
	)
)
